# T6G (Grand Teton) — schematic netlist excerpt (pin names and nets, part order shuffled) for the footprints in the layout excerpt that follows; sources: Cadence DE-HDL packaged netlist, KiCad conversion of 04192023_DAF0TMB3IC0_F0TG_MB_C_brd_V02_OCP.brd

R97  Q_RES  1K 1% EMPTY  pkg 0402LF  page 93 : A = P3V3 ; B = PWRGD_CHH_CPU0_DIMM
PR8005  Q_RES  0 5% CHIP  pkg 0402LF  page 193 : A = SVID_PVDDCR_CPU0_P0_SVC_R ; B = SVID_PVDDCR_CPU0_P0_SVC_R1

(kicad_pcb
	(version 20260206)
	(generator "pcbnew")
	(generator_version "10.0")
	(general
		(thickness 1.6)
		(legacy_teardrops no)
	)
	(paper "A4")
	(title_block
		(title "04192023_DAF0TMB3IC0_F0TG_MB_C_brd_V02_OCP.brd")
		(comment 1 "Grand Teton / footprints 6133-6134 of 8354")
	)
	(layers
		(0 "F.Cu" signal "TOP")
		(4 "In1.Cu" signal "GND")
		(6 "In2.Cu" signal "IN1")
		(8 "In3.Cu" signal "GND1")
		(10 "In4.Cu" signal "IN2")
		(12 "In5.Cu" signal "GND2")
		(14 "In6.Cu" signal "IN3")
		(16 "In7.Cu" signal "GND3")
		(18 "In8.Cu" signal "VCC")
		(20 "In9.Cu" signal "VCC1")
		(22 "In10.Cu" signal "GND4")
		(24 "In11.Cu" signal "IN4")
		(26 "In12.Cu" signal "GND5")
		(28 "In13.Cu" signal "IN5")
		(30 "In14.Cu" signal "GND6")
		(32 "In15.Cu" signal "IN6")
		(34 "In16.Cu" signal "GND7")
		(2 "B.Cu" signal "BOTTOM")
		(9 "F.Adhes" user "F.Adhesive")
		(11 "B.Adhes" user "B.Adhesive")
		(13 "F.Paste" user "Package Geometry/Pastemask Top")
		(15 "B.Paste" user "Package Geometry/Pastemask Bottom")
		(5 "F.SilkS" user "Ref Des/Silkscreen Top")
		(7 "B.SilkS" user "Ref Des/Silkscreen Bottom")
		(1 "F.Mask" user "Board Geometry/Soldermask Top")
		(3 "B.Mask" user "Board Geometry/Soldermask Bottom")
		(17 "Dwgs.User" user "User.Drawings")
		(19 "Cmts.User" user "User.Comments")
		(21 "Eco1.User" user "User.Eco1")
		(23 "Eco2.User" user "User.Eco2")
		(25 "Edge.Cuts" user "Board Geometry/Outline")
		(27 "Margin" user)
		(31 "F.CrtYd" user "Package Geometry/Place Bound Top")
		(29 "B.CrtYd" user "Package Geometry/Place Bound Bottom")
		(35 "F.Fab" user "Ref Des/Assembly Top")
		(33 "B.Fab" user "Ref Des/Assembly Bottom")
	)
	(footprint ""
		(layer "B.Cu")
		(at 372.937278 -145.536158 180)
		(property "Reference" "PR8005"
			(at 0 0 0)
			(layer "B.SilkS")
			(hide yes)
			(effects
				(font
					(size 1.27 1.27)
				)
				(justify mirror)
			)
		)
		(property "Value" ""
			(at 0 0 0)
			(layer "B.Fab")
			(effects
				(font
					(size 1.27 1.27)
				)
				(justify mirror)
			)
		)
		(duplicate_pad_numbers_are_jumpers no)
		(fp_line
			(start 0.7874 0.4064)
			(end 0.7874 -0.4064)
			(stroke
				(width 0.1524)
				(type default)
			)
			(layer "B.SilkS")
		)
		(fp_line
			(start 0.7874 -0.4064)
			(end -0.7874 -0.4064)
			(stroke
				(width 0.1524)
				(type default)
			)
			(layer "B.SilkS")
		)
		(fp_line
			(start -0.7874 0.4064)
			(end 0.7874 0.4064)
			(stroke
				(width 0.1524)
				(type default)
			)
			(layer "B.SilkS")
		)
		(fp_line
			(start -0.7874 -0.4064)
			(end -0.7874 0.4064)
			(stroke
				(width 0.1524)
				(type default)
			)
			(layer "B.SilkS")
		)
		(fp_line
			(start 0.67945 0.3048)
			(end 0.67945 -0.305054)
			(stroke
				(width 0.1)
				(type default)
			)
			(layer "B.Fab")
		)
		(fp_line
			(start 0.67945 -0.305054)
			(end 0.12065 -0.305054)
			(stroke
				(width 0.1)
				(type default)
			)
			(layer "B.Fab")
		)
		(fp_line
			(start 0.12065 0.3048)
			(end 0.67945 0.3048)
			(stroke
				(width 0.1)
				(type default)
			)
			(layer "B.Fab")
		)
		(fp_line
			(start 0.12065 0.2794)
			(end 0.12065 0.3048)
			(stroke
				(width 0.1)
				(type default)
			)
			(layer "B.Fab")
		)
		(fp_line
			(start 0.12065 -0.2794)
			(end -0.12065 -0.2794)
			(stroke
				(width 0.1)
				(type default)
			)
			(layer "B.Fab")
		)
		(fp_line
			(start 0.12065 -0.305054)
			(end 0.12065 -0.2794)
			(stroke
				(width 0.1)
				(type default)
			)
			(layer "B.Fab")
		)
		(fp_line
			(start -0.120396 0.3048)
			(end -0.120396 0.2794)
			(stroke
				(width 0.1)
				(type default)
			)
			(layer "B.Fab")
		)
		(fp_line
			(start -0.120396 0.2794)
			(end 0.12065 0.2794)
			(stroke
				(width 0.1)
				(type default)
			)
			(layer "B.Fab")
		)
		(fp_line
			(start -0.12065 -0.2794)
			(end -0.12065 -0.3048)
			(stroke
				(width 0.1)
				(type default)
			)
			(layer "B.Fab")
		)
		(fp_line
			(start -0.12065 -0.3048)
			(end -0.67945 -0.3048)
			(stroke
				(width 0.1)
				(type default)
			)
			(layer "B.Fab")
		)
		(fp_line
			(start -0.67945 0.3048)
			(end -0.120396 0.3048)
			(stroke
				(width 0.1)
				(type default)
			)
			(layer "B.Fab")
		)
		(fp_line
			(start -0.67945 -0.3048)
			(end -0.67945 0.3048)
			(stroke
				(width 0.1)
				(type default)
			)
			(layer "B.Fab")
		)
		(pad "1" smd circle
			(at 0.40005 0)
			(size 0 0)
			(layers "B.Cu" "B.Mask" "B.Paste")
			(net "SVID_PVDDCR_CPU0_P0_SVC_R")
		)
		(pad "2" smd circle
			(at -0.40005 0)
			(size 0 0)
			(layers "B.Cu" "B.Mask" "B.Paste")
			(net "SVID_PVDDCR_CPU0_P0_SVC_R1")
		)
	)
	(footprint ""
		(layer "B.Cu")
		(at 420.667688 -193.99631)
		(property "Reference" "R97"
			(at 0 0 0)
			(layer "B.SilkS")
			(hide yes)
			(effects
				(font
					(size 1.27 1.27)
				)
				(justify mirror)
			)
		)
		(property "Value" ""
			(at 0 0 0)
			(layer "B.Fab")
			(effects
				(font
					(size 1.27 1.27)
				)
				(justify mirror)
			)
		)
		(duplicate_pad_numbers_are_jumpers no)
		(fp_line
			(start -0.7874 -0.4064)
			(end -0.7874 0.4064)
			(stroke
				(width 0.1524)
				(type default)
			)
			(layer "B.SilkS")
		)
		(fp_line
			(start -0.7874 0.4064)
			(end 0.7874 0.4064)
			(stroke
				(width 0.1524)
				(type default)
			)
			(layer "B.SilkS")
		)
		(fp_line
			(start 0.7874 -0.4064)
			(end -0.7874 -0.4064)
			(stroke
				(width 0.1524)
				(type default)
			)
			(layer "B.SilkS")
		)
		(fp_line
			(start 0.7874 0.4064)
			(end 0.7874 -0.4064)
			(stroke
				(width 0.1524)
				(type default)
			)
			(layer "B.SilkS")
		)
		(fp_line
			(start -0.67945 -0.3048)
			(end -0.67945 0.3048)
			(stroke
				(width 0.1)
				(type default)
			)
			(layer "B.Fab")
		)
		(fp_line
			(start -0.67945 0.3048)
			(end -0.120396 0.3048)
			(stroke
				(width 0.1)
				(type default)
			)
			(layer "B.Fab")
		)
		(fp_line
			(start -0.12065 -0.3048)
			(end -0.67945 -0.3048)
			(stroke
				(width 0.1)
				(type default)
			)
			(layer "B.Fab")
		)
		(fp_line
			(start -0.12065 -0.2794)
			(end -0.12065 -0.3048)
			(stroke
				(width 0.1)
				(type default)
			)
			(layer "B.Fab")
		)
		(fp_line
			(start -0.120396 0.2794)
			(end 0.12065 0.2794)
			(stroke
				(width 0.1)
				(type default)
			)
			(layer "B.Fab")
		)
		(fp_line
			(start -0.120396 0.3048)
			(end -0.120396 0.2794)
			(stroke
				(width 0.1)
				(type default)
			)
			(layer "B.Fab")
		)
		(fp_line
			(start 0.12065 -0.305054)
			(end 0.12065 -0.2794)
			(stroke
				(width 0.1)
				(type default)
			)
			(layer "B.Fab")
		)
		(fp_line
			(start 0.12065 -0.2794)
			(end -0.12065 -0.2794)
			(stroke
				(width 0.1)
				(type default)
			)
			(layer "B.Fab")
		)
		(fp_line
			(start 0.12065 0.2794)
			(end 0.12065 0.3048)
			(stroke
				(width 0.1)
				(type default)
			)
			(layer "B.Fab")
		)
		(fp_line
			(start 0.12065 0.3048)
			(end 0.67945 0.3048)
			(stroke
				(width 0.1)
				(type default)
			)
			(layer "B.Fab")
		)
		(fp_line
			(start 0.67945 -0.305054)
			(end 0.12065 -0.305054)
			(stroke
				(width 0.1)
				(type default)
			)
			(layer "B.Fab")
		)
		(fp_line
			(start 0.67945 0.3048)
			(end 0.67945 -0.305054)
			(stroke
				(width 0.1)
				(type default)
			)
			(layer "B.Fab")
		)
		(pad "1" smd circle
			(at 0.40005 0 180)
			(size 0 0)
			(layers "B.Cu" "B.Mask" "B.Paste")
			(net "P3V3")
		)
		(pad "2" smd circle
			(at -0.40005 0 180)
			(size 0 0)
			(layers "B.Cu" "B.Mask" "B.Paste")
			(net "PWRGD_CHH_CPU0_DIMM")
		)
	)
)
